(kicad_pcb
	(version 20221018)
	(generator pcbnew)
	(general
    (thickness 1.7403)
  )
	(paper "A4")
	(title_block
    (title "Data Center RDIMM DDR4 Tester")
    (date "2024-09-30")
    (rev "1.2.4")
		(comment 9 "footprints 544-549 of 690")
	)
	(layers
    (0 "F.Cu" signal)
    (1 "In1.Cu" power)
    (2 "In2.Cu" signal)
    (3 "In3.Cu" power)
    (4 "In4.Cu" power)
    (5 "In5.Cu" signal)
    (6 "In6.Cu" power)
    (7 "In7.Cu" signal)
    (8 "In8.Cu" power)
    (9 "In9.Cu" signal)
    (10 "In10.Cu" power)
    (31 "B.Cu" signal)
    (32 "B.Adhes" user "B.Adhesive")
    (33 "F.Adhes" user "F.Adhesive")
    (34 "B.Paste" user)
    (35 "F.Paste" user)
    (36 "B.SilkS" user "B.Silkscreen")
    (37 "F.SilkS" user "F.Silkscreen")
    (38 "B.Mask" user)
    (39 "F.Mask" user)
    (40 "Dwgs.User" user "User.Drawings")
    (41 "Cmts.User" user "User.Comments")
    (42 "Eco1.User" user "User.Eco1")
    (43 "Eco2.User" user "User.Eco2")
    (44 "Edge.Cuts" user)
    (45 "Margin" user)
    (46 "B.CrtYd" user "B.Courtyard")
    (47 "F.CrtYd" user "F.Courtyard")
    (48 "B.Fab" user)
    (49 "F.Fab" user)
  )
	(footprint "data-center-rdimm-ddr4-tester-footprints:C_0201" (layer "B.Cu")
    (at 194.1 95.6 180)
    (descr "Capacitor SMD 0201")
    (tags "capacitor SMD 0201")
    (property "Author" "Antmicro")
    (property "Dielectric" "")
    (property "License" "Apache-2.0")
    (property "MPN" "CC0201KRX6S5BB104")
    (property "Manufacturer" "Yaego")
    (property "Sheetfile" "fpga-power.kicad_sch")
    (property "Sheetname" "FPGA power")
    (property "Val" "100n")
    (property "Voltage" "")
    (property "ki_description" " ")
    (attr smd)
    (fp_text reference "C251" (at -6.28 -0.36) (layer "B.SilkS")
        (effects (font (size 0.7 0.7) (thickness 0.15)) (justify left bottom mirror))
    )
    (fp_text value "C_100n_0201" (at 0 -1.4) (layer "B.Fab") hide
        (effects (font (size 0.7 0.7) (thickness 0.15)) (justify left bottom mirror))
    )
    (fp_text user "Author: Antmicro" (at -0.72 -5.4) (layer "B.Fab") hide
        (effects (font (size 0.7 0.7) (thickness 0.15)) (justify left bottom mirror))
    )
    (fp_text user "${REFERENCE}" (at -0.72 -3.4) (layer "B.Fab") hide
        (effects (font (size 0.7 0.7) (thickness 0.15)) (justify left bottom mirror))
    )
    (fp_text user "License: Apache-2.0" (at -0.72 -4.4) (layer "B.Fab") hide
        (effects (font (size 0.7 0.7) (thickness 0.15)) (justify left bottom mirror))
    )
    (fp_rect (start -0.72 0.38) (end 0.72 -0.38)
      (stroke (width 0.05) (type solid)) (fill none) (layer "B.CrtYd"))
    (fp_rect (start 0.3 -0.15) (end -0.301 0.149)
      (stroke (width 0.15) (type solid)) (fill none) (layer "B.Fab"))
    (pad "" smd roundrect (at -0.349 0.002 180) (size 0.318 0.36) (layers "B.Paste") (roundrect_rratio 0.25))
    (pad "" smd roundrect (at 0.341 0.002 180) (size 0.318 0.36) (layers "B.Paste") (roundrect_rratio 0.25))
    (pad "1" smd roundrect (at -0.321 0.002 180) (size 0.46 0.4) (layers "B.Cu" "B.Mask") (roundrect_rratio 0.25)
      (net 306 "1V2_SYS") (pintype "passive"))
    (pad "2" smd roundrect (at 0.32 0.002 180) (size 0.46 0.4) (layers "B.Cu" "B.Mask") (roundrect_rratio 0.25)
      (net 9 "GND") (pintype "passive"))
  )
	(footprint "data-center-rdimm-ddr4-tester-footprints:R_0402_1005Metric" (layer "B.Cu")
    (at 176.25 129.105 180)
    (descr "Resistor SMD 0402")
    (tags "resistor SMD 0402")
    (property "Author" "Antmicro")
    (property "DNP" "DNP")
    (property "License" "Apache-2.0")
    (property "MPN" "CR0402-FX-1002GLF")
    (property "Manufacturer" "Bourns")
    (property "Sheetfile" "ethernet.kicad_sch")
    (property "Sheetname" "Ethernet")
    (property "Tolerance" "1%")
    (property "Val" "10k")
    (property "dnp" "")
    (property "exclude_from_bom" "")
    (property "ki_description" "10k resistor in 0402 package with 1% tolerance")
    (attr exclude_from_pos_files exclude_from_bom)
    (fp_text reference "R181" (at 0.73 -0.445) (layer "B.SilkS")
        (effects (font (size 0.7 0.7) (thickness 0.15)) (justify left bottom mirror))
    )
    (fp_text value "R_10k_0402" (at 0 -1.4) (layer "B.Fab") hide
        (effects (font (size 0.7 0.7) (thickness 0.15)) (justify left bottom mirror))
    )
    (fp_text user "License: Apache-2.0" (at -0.95 -5.169) (layer "B.Fab") hide
        (effects (font (size 0.7 0.7) (thickness 0.15)) (justify left bottom mirror))
    )
    (fp_text user "Author: Antmicro" (at -0.95 -4.169) (layer "B.Fab") hide
        (effects (font (size 0.7 0.7) (thickness 0.15)) (justify left bottom mirror))
    )
    (fp_text user "${REFERENCE}" (at -0.95 -3.168) (layer "B.Fab") hide
        (effects (font (size 0.7 0.7) (thickness 0.15)) (justify left bottom mirror))
    )
    (fp_rect (start -0.93 0.47) (end 0.93 -0.47)
      (stroke (width 0.05) (type solid)) (fill none) (layer "B.CrtYd"))
    (fp_rect (start -0.5 0.25) (end 0.5 -0.25)
      (stroke (width 0.15) (type solid)) (fill none) (layer "B.Fab"))
    (pad "1" smd roundrect (at -0.485 0 180) (size 0.59 0.64) (layers "B.Cu" "B.Paste" "B.Mask") (roundrect_rratio 0.25)
      (net 622 "/Ethernet/TPL") (pintype "passive"))
    (pad "2" smd roundrect (at 0.485 0 180) (size 0.59 0.64) (layers "B.Cu" "B.Paste" "B.Mask") (roundrect_rratio 0.25)
      (net 360 "/Ethernet/VDD") (pintype "passive"))
  )
	(footprint "data-center-rdimm-ddr4-tester-footprints:C_0402_1005Metric" (layer "B.Cu")
    (at 216.087 89.607 90)
    (descr "Capacitor SMD 0402")
    (tags "capacitor SMD 0402")
    (property "Author" "Antmicro")
    (property "Dielectric" "X5R")
    (property "License" "Apache-2.0")
    (property "MPN" "GRM155R61H104KE14D")
    (property "Manufacturer" "Murata")
    (property "Sheetfile" "fpga-power.kicad_sch")
    (property "Sheetname" "FPGA power")
    (property "Val" "100n")
    (property "Voltage" "50V")
    (property "ki_description" " ")
    (attr smd)
    (fp_text reference "C314" (at 1.317 1.333 270) (layer "B.SilkS")
        (effects (font (size 0.7 0.7) (thickness 0.15)) (justify left bottom mirror))
    )
    (fp_text value "C_100n_0402" (at 0 -1.4 270) (layer "B.Fab") hide
        (effects (font (size 0.7 0.7) (thickness 0.15)) (justify left bottom mirror))
    )
    (fp_text user "${REFERENCE}" (at -0.932 -3.168 270) (layer "B.Fab") hide
        (effects (font (size 0.7 0.7) (thickness 0.15)) (justify left bottom mirror))
    )
    (fp_text user "Author: Antmicro" (at -0.932 -4.17 270) (layer "B.Fab") hide
        (effects (font (size 0.7 0.7) (thickness 0.15)) (justify left bottom mirror))
    )
    (fp_text user "License: Apache-2.0" (at -0.932 -5.17 270) (layer "B.Fab") hide
        (effects (font (size 0.7 0.7) (thickness 0.15)) (justify left bottom mirror))
    )
    (fp_rect (start -0.94 0.47) (end 0.94 -0.47)
      (stroke (width 0.05) (type solid)) (fill none) (layer "B.CrtYd"))
    (fp_rect (start -0.499 0.249) (end 0.499 -0.249)
      (stroke (width 0.15) (type solid)) (fill none) (layer "B.Fab"))
    (pad "1" smd roundrect (at -0.484 0 90) (size 0.59 0.64) (layers "B.Cu" "B.Paste" "B.Mask") (roundrect_rratio 0.25)
      (net 306 "1V2_SYS") (pintype "passive"))
    (pad "2" smd roundrect (at 0.484 0 90) (size 0.59 0.64) (layers "B.Cu" "B.Paste" "B.Mask") (roundrect_rratio 0.25)
      (net 9 "GND") (pintype "passive"))
  )
	(footprint "data-center-rdimm-ddr4-tester-footprints:R_0603_1608Metric" (layer "B.Cu")
    (at 189.26 84.89 180)
    (descr "Resistor SMD 0603")
    (tags "resistor SMD 0603")
    (property "Author" "Antmicro")
    (property "License" "Apache-2.0")
    (property "MPN" "CR0603-FX-80R6ELF")
    (property "Manufacturer" "Bourns")
    (property "Sheetfile" "fpga-banks-16-34.kicad_sch")
    (property "Sheetname" "FPGA banks 16-34")
    (property "Tolerance" "1%")
    (property "Val" "80R6")
    (property "ki_description" "80R6 resistor in 0603 package with 1% tolerance")
    (attr smd)
    (fp_text reference "R63" (at 0.98 -0.23) (layer "B.SilkS")
        (effects (font (size 0.7 0.7) (thickness 0.15)) (justify left bottom mirror))
    )
    (fp_text value "R_80R6_0603" (at 0 -1.6) (layer "B.Fab") hide
        (effects (font (size 0.7 0.7) (thickness 0.15)) (justify left bottom mirror))
    )
    (fp_text user "Author: Antmicro" (at -1.25 -4.9) (layer "B.Fab") hide
        (effects (font (size 0.7 0.7) (thickness 0.15)) (justify left bottom mirror))
    )
    (fp_text user "License: Apache-2.0" (at -1.25 -5.9) (layer "B.Fab") hide
        (effects (font (size 0.7 0.7) (thickness 0.15)) (justify left bottom mirror))
    )
    (fp_text user "${REFERENCE}" (at -1.25 -3.898) (layer "B.Fab") hide
        (effects (font (size 0.7 0.7) (thickness 0.15)) (justify left bottom mirror))
    )
    (fp_line (start -0.3 -0.3) (end 0.3 -0.3)
      (stroke (width 0.15) (type solid)) (layer "B.SilkS"))
    (fp_line (start -0.3 0.3) (end 0.3 0.3)
      (stroke (width 0.15) (type solid)) (layer "B.SilkS"))
    (fp_rect (start -1.25 0.7) (end 1.25 -0.7)
      (stroke (width 0.05) (type solid)) (fill none) (layer "B.CrtYd"))
    (fp_rect (start -0.8 0.4) (end 0.8 -0.4)
      (stroke (width 0.15) (type solid)) (fill none) (layer "B.Fab"))
    (pad "1" smd roundrect (at -0.7 0 180) (size 0.6 0.8) (layers "B.Cu" "B.Paste" "B.Mask") (roundrect_rratio 0.2)
      (net 309 "VRN") (pintype "passive"))
    (pad "2" smd roundrect (at 0.7 0 180) (size 0.6 0.8) (layers "B.Cu" "B.Paste" "B.Mask") (roundrect_rratio 0.2)
      (net 77 "VDDQ") (pintype "passive"))
  )
	(footprint "data-center-rdimm-ddr4-tester-footprints:VQFN-20_5x5x1mm_P0.65mm" (layer "B.Cu")
    (at 181.01 128.61 -90)
    (property "Author" "Antmicro")
    (property "License" "Apache-2.0")
    (property "MPN" "TPS2372-3RGWR")
    (property "Manufacturer" "Texas Instruments")
    (property "Sheetfile" "ethernet.kicad_sch")
    (property "Sheetname" "Ethernet")
    (property "ki_description" "IEEE 802.3bt PoE high-power PD interface with automatic MPS & autoclass")
    (property "ki_keywords" "IEEE 802.3bt PoE high-power PD interface with automatic MPS & autoclass")
    (attr smd)
    (fp_text reference "U13" (at 2.91 2.48 180) (layer "B.SilkS")
        (effects (font (size 0.7 0.7) (thickness 0.15)) (justify left bottom mirror))
    )
    (fp_text value "TPS2372-3RGWR" (at 0 -3.883 90) (layer "B.Fab") hide
        (effects (font (size 0.7 0.7) (thickness 0.15)) (justify left bottom mirror))
    )
    (fp_text user "License: Apache-2.0" (at -2.5 -7.884 90) (layer "B.Fab") hide
        (effects (font (size 0.7 0.7) (thickness 0.15)) (justify left bottom mirror))
    )
    (fp_text user "Author: Antmicro" (at -2.5 -6.884 90) (layer "B.Fab") hide
        (effects (font (size 0.7 0.7) (thickness 0.15)) (justify left bottom mirror))
    )
    (fp_text user "${REFERENCE}" (at -2.5 -5.884 90) (layer "B.Fab") hide
        (effects (font (size 0.7 0.7) (thickness 0.15)) (justify left bottom mirror))
    )
    (fp_poly
      (pts
        (xy -1.081 -0.088)
        (xy -0.11 -0.088)
        (xy -0.11 -1.08)
        (xy -1.081 -1.08)
      )

      (stroke (width 0.01) (type solid)) (fill solid) (layer "B.Paste"))
    (fp_poly
      (pts
        (xy -1.081 1.081)
        (xy -0.11 1.081)
        (xy -0.11 0.09)
        (xy -1.081 0.09)
      )

      (stroke (width 0.01) (type solid)) (fill solid) (layer "B.Paste"))
    (fp_poly
      (pts
        (xy 0.108 -0.088)
        (xy 1.08 -0.088)
        (xy 1.08 -1.08)
        (xy 0.108 -1.08)
      )

      (stroke (width 0.01) (type solid)) (fill solid) (layer "B.Paste"))
    (fp_poly
      (pts
        (xy 0.108 1.081)
        (xy 1.08 1.081)
        (xy 1.08 0.09)
        (xy 0.108 0.09)
      )

      (stroke (width 0.01) (type solid)) (fill solid) (layer "B.Paste"))
    (fp_line (start -2.5 -2.499) (end -2.5 -1.789)
      (stroke (width 0.15) (type solid)) (layer "B.SilkS"))
    (fp_line (start -2.5 -2.499) (end -1.79 -2.499)
      (stroke (width 0.15) (type solid)) (layer "B.SilkS"))
    (fp_line (start -1.625 2.5) (end -2.5 2.5)
      (stroke (width 0.15) (type solid)) (layer "B.SilkS"))
    (fp_line (start 2.499 -2.499) (end 1.789 -2.499)
      (stroke (width 0.15) (type solid)) (layer "B.SilkS"))
    (fp_line (start 2.499 -2.499) (end 2.499 -1.789)
      (stroke (width 0.15) (type solid)) (layer "B.SilkS"))
    (fp_line (start 2.499 2.5) (end 1.789 2.5)
      (stroke (width 0.15) (type solid)) (layer "B.SilkS"))
    (fp_line (start 2.499 2.5) (end 2.499 1.79)
      (stroke (width 0.15) (type solid)) (layer "B.SilkS"))
    (fp_circle (center -2.775 1.875) (end -2.725 1.825)
      (stroke (width 0.15) (type solid)) (fill solid) (layer "B.SilkS"))
    (fp_rect (start -2.95 2.95) (end 2.95 -2.95)
      (stroke (width 0.05) (type solid)) (fill none) (layer "B.CrtYd"))
    (fp_line (start -2.5 -2.499) (end -2.5 1.65)
      (stroke (width 0.15) (type solid)) (layer "B.Fab"))
    (fp_line (start -2.5 1.65) (end -1.65 2.5)
      (stroke (width 0.15) (type solid)) (layer "B.Fab"))
    (fp_line (start 2.499 -2.499) (end -2.5 -2.499)
      (stroke (width 0.15) (type solid)) (layer "B.Fab"))
    (fp_line (start 2.499 -2.499) (end 2.499 2.5)
      (stroke (width 0.15) (type solid)) (layer "B.Fab"))
    (fp_line (start 2.499 2.5) (end -1.65 2.5)
      (stroke (width 0.15) (type solid)) (layer "B.Fab"))
    (pad "1" smd roundrect (at -2.327 1.301 270) (size 0.75 0.31) (layers "B.Cu" "B.Paste" "B.Mask") (roundrect_rratio 0.25)
      (net 360 "/Ethernet/VDD") (pinfunction "VDD") (pintype "power_in"))
    (pad "2" smd roundrect (at -2.327 0.652 270) (size 0.75 0.31) (layers "B.Cu" "B.Paste" "B.Mask") (roundrect_rratio 0.25)
      (net 610 "/Ethernet/DEN") (pinfunction "DEN") (pintype "input"))
    (pad "3" smd roundrect (at -2.327 0 270) (size 0.75 0.31) (layers "B.Cu" "B.Paste" "B.Mask") (roundrect_rratio 0.25)
      (net 611 "/Ethernet/CLSA") (pinfunction "CLSA") (pintype "input"))
    (pad "4" smd roundrect (at -2.327 -0.65 270) (size 0.75 0.31) (layers "B.Cu" "B.Paste" "B.Mask") (roundrect_rratio 0.25)
      (net 381 "/Ethernet/VSS") (pinfunction "VSSA") (pintype "power_in"))
    (pad "5" smd roundrect (at -2.327 -1.3 270) (size 0.75 0.31) (layers "B.Cu" "B.Paste" "B.Mask") (roundrect_rratio 0.25)
      (net 381 "/Ethernet/VSS") (pinfunction "VSSB") (pintype "power_in"))
    (pad "6" smd roundrect (at -1.301 -2.325 270) (size 0.31 0.75) (layers "B.Cu" "B.Paste" "B.Mask") (roundrect_rratio 0.25)
      (net 618 "/Ethernet/CLSB") (pinfunction "CLSB") (pintype "input"))
    (pad "7" smd roundrect (at -0.652 -2.325 270) (size 0.31 0.75) (layers "B.Cu" "B.Paste" "B.Mask") (roundrect_rratio 0.25)
      (net 617 "/Ethernet/REF") (pinfunction "REF") (pintype "input"))
    (pad "8" smd roundrect (at 0 -2.325 270) (size 0.31 0.75) (layers "B.Cu" "B.Paste" "B.Mask") (roundrect_rratio 0.25)
      (net 612 "/Ethernet/AMPS_CTL") (pinfunction "AMPS_CTL") (pintype "input"))
    (pad "9" smd roundrect (at 0.65 -2.325 270) (size 0.31 0.75) (layers "B.Cu" "B.Paste" "B.Mask") (roundrect_rratio 0.25)
      (net 629 "/Ethernet/MPS_DUTY") (pinfunction "MPS_DUTY") (pintype "input"))
    (pad "10" smd roundrect (at 1.3 -2.325 270) (size 0.31 0.75) (layers "B.Cu" "B.Paste" "B.Mask") (roundrect_rratio 0.25)
      (net 701 "unconnected-(U13-~{AUTCLS}-Pad10)") (pinfunction "~{AUTCLS}") (pintype "input+no_connect"))
    (pad "11" smd roundrect (at 2.325 -1.3 270) (size 0.75 0.31) (layers "B.Cu" "B.Paste" "B.Mask") (roundrect_rratio 0.25)
      (net 604 "GNDD") (pinfunction "RTNA") (pintype "output"))
    (pad "12" smd roundrect (at 2.325 -0.65 270) (size 0.75 0.31) (layers "B.Cu" "B.Paste" "B.Mask") (roundrect_rratio 0.25)
      (net 604 "GNDD") (pinfunction "RTNB") (pintype "output"))
    (pad "13" smd roundrect (at 2.325 0 270) (size 0.75 0.31) (layers "B.Cu" "B.Paste" "B.Mask") (roundrect_rratio 0.25)
      (net 620 "/Ethernet/PG") (pinfunction "PG") (pintype "output"))
    (pad "14" smd roundrect (at 2.325 0.652 270) (size 0.75 0.31) (layers "B.Cu" "B.Paste" "B.Mask") (roundrect_rratio 0.25)
      (net 702 "unconnected-(U13-NC-Pad14)") (pinfunction "NC") (pintype "no_connect"))
    (pad "15" smd roundrect (at 2.325 1.301 270) (size 0.75 0.31) (layers "B.Cu" "B.Paste" "B.Mask") (roundrect_rratio 0.25)
      (net 703 "unconnected-(U13-NC-Pad15)") (pinfunction "NC") (pintype "no_connect"))
    (pad "16" smd roundrect (at 1.3 2.327 270) (size 0.31 0.75) (layers "B.Cu" "B.Paste" "B.Mask") (roundrect_rratio 0.25)
      (net 621 "/Ethernet/IRSHDL_EN") (pinfunction "IRSHDL_EN") (pintype "output"))
    (pad "17" smd roundrect (at 0.65 2.327 270) (size 0.31 0.75) (layers "B.Cu" "B.Paste" "B.Mask") (roundrect_rratio 0.25)
      (net 622 "/Ethernet/TPL") (pinfunction "TPL") (pintype "output"))
    (pad "18" smd roundrect (at 0 2.327 270) (size 0.31 0.75) (layers "B.Cu" "B.Paste" "B.Mask") (roundrect_rratio 0.25)
      (net 619 "/Ethernet/TPH") (pinfunction "TPH") (pintype "output"))
    (pad "19" smd roundrect (at -0.652 2.327 270) (size 0.31 0.75) (layers "B.Cu" "B.Paste" "B.Mask") (roundrect_rratio 0.25)
      (net 659 "Net-(U13-~{BT})") (pinfunction "~{BT}") (pintype "output"))
    (pad "20" smd roundrect (at -1.301 2.327 270) (size 0.31 0.75) (layers "B.Cu" "B.Paste" "B.Mask") (roundrect_rratio 0.25)
      (net 704 "unconnected-(U13-NC-Pad20)") (pinfunction "NC") (pintype "no_connect"))
    (pad "21" smd rect (at 0 0 270) (size 2.2 2.2) (layers "B.Cu" "B.Mask")
      (net 381 "/Ethernet/VSS") (pinfunction "PAD_VSSC") (pintype "power_in"))
  )
	(footprint "data-center-rdimm-ddr4-tester-footprints:R_0402_1005Metric" (layer "B.Cu")
    (at 226.25 122.85 -90)
    (descr "Resistor SMD 0402")
    (tags "resistor SMD 0402")
    (property "Author" "Antmicro")
    (property "Current" "1A")
    (property "DNP" "DNP")
    (property "License" "Apache-2.0")
    (property "MPN" "ERJ2GE0R00X")
    (property "Manufacturer" "Panasonic")
    (property "Sheetfile" "supply.kicad_sch")
    (property "Sheetname" "Supply")
    (property "Tolerance" "")
    (property "Val" "0R")
    (property "dnp" "")
    (property "exclude_from_bom" "")
    (property "ki_description" "0R resistor in 0402 package with unspecified tolerance")
    (attr exclude_from_pos_files exclude_from_bom)
    (fp_text reference "R219" (at -1.4 0.56 90) (layer "B.SilkS")
        (effects (font (size 0.7 0.7) (thickness 0.15)) (justify left bottom mirror))
    )
    (fp_text value "R_0R_0402" (at 0 -1.4 90) (layer "B.Fab") hide
        (effects (font (size 0.7 0.7) (thickness 0.15)) (justify left bottom mirror))
    )
    (fp_text user "License: Apache-2.0" (at -0.95 -5.169 90) (layer "B.Fab") hide
        (effects (font (size 0.7 0.7) (thickness 0.15)) (justify left bottom mirror))
    )
    (fp_text user "Author: Antmicro" (at -0.95 -4.169 90) (layer "B.Fab") hide
        (effects (font (size 0.7 0.7) (thickness 0.15)) (justify left bottom mirror))
    )
    (fp_text user "${REFERENCE}" (at -0.95 -3.168 90) (layer "B.Fab") hide
        (effects (font (size 0.7 0.7) (thickness 0.15)) (justify left bottom mirror))
    )
    (fp_rect (start -0.93 0.47) (end 0.93 -0.47)
      (stroke (width 0.05) (type solid)) (fill none) (layer "B.CrtYd"))
    (fp_rect (start -0.5 0.25) (end 0.5 -0.25)
      (stroke (width 0.15) (type solid)) (fill none) (layer "B.Fab"))
    (pad "1" smd roundrect (at -0.485 0 270) (size 0.59 0.64) (layers "B.Cu" "B.Paste" "B.Mask") (roundrect_rratio 0.25)
      (net 119 "/Supply/~{INT}") (pintype "passive"))
    (pad "2" smd roundrect (at 0.485 0 270) (size 0.59 0.64) (layers "B.Cu" "B.Paste" "B.Mask") (roundrect_rratio 0.25)
      (net 860 "/Supply/~{CLR}") (pintype "passive"))
  )
)
